(kicad_pcb
	(version 20260206)
	(generator "pcbnew")
	(generator_version "10.0")
	(general
		(thickness 1.6)
		(legacy_teardrops no)
	)
	(paper "A4")
	(title_block
		(title "04192023_DAF0TMB3IC0_F0TG_MB_C_brd_V02_OCP.brd")
		(comment 1 "Grand Teton / footprints 4360-4364 of 8354")
	)
	(layers
		(0 "F.Cu" signal "TOP")
		(4 "In1.Cu" signal "GND")
		(6 "In2.Cu" signal "IN1")
		(8 "In3.Cu" signal "GND1")
		(10 "In4.Cu" signal "IN2")
		(12 "In5.Cu" signal "GND2")
		(14 "In6.Cu" signal "IN3")
		(16 "In7.Cu" signal "GND3")
		(18 "In8.Cu" signal "VCC")
		(20 "In9.Cu" signal "VCC1")
		(22 "In10.Cu" signal "GND4")
		(24 "In11.Cu" signal "IN4")
		(26 "In12.Cu" signal "GND5")
		(28 "In13.Cu" signal "IN5")
		(30 "In14.Cu" signal "GND6")
		(32 "In15.Cu" signal "IN6")
		(34 "In16.Cu" signal "GND7")
		(2 "B.Cu" signal "BOTTOM")
		(9 "F.Adhes" user "F.Adhesive")
		(11 "B.Adhes" user "B.Adhesive")
		(13 "F.Paste" user "Package Geometry/Pastemask Top")
		(15 "B.Paste" user "Package Geometry/Pastemask Bottom")
		(5 "F.SilkS" user "Ref Des/Silkscreen Top")
		(7 "B.SilkS" user "Ref Des/Silkscreen Bottom")
		(1 "F.Mask" user "Board Geometry/Soldermask Top")
		(3 "B.Mask" user "Board Geometry/Soldermask Bottom")
		(17 "Dwgs.User" user "User.Drawings")
		(19 "Cmts.User" user "User.Comments")
		(21 "Eco1.User" user "User.Eco1")
		(23 "Eco2.User" user "User.Eco2")
		(25 "Edge.Cuts" user "Board Geometry/Outline")
		(27 "Margin" user)
		(31 "F.CrtYd" user "Package Geometry/Place Bound Top")
		(29 "B.CrtYd" user "Package Geometry/Place Bound Bottom")
		(35 "F.Fab" user "Ref Des/Assembly Top")
		(33 "B.Fab" user "Ref Des/Assembly Bottom")
	)
	(footprint ""
		(layer "F.Cu")
		(at 234.739688 -156.314648 180)
		(property "Reference" "U14"
			(at -3.930904 -1.816608 0)
			(unlocked yes)
			(layer "F.SilkS")
			(effects
				(font
					(size 0.7874 0.5842)
					(thickness 0.1524)
				)
				(justify left)
			)
		)
		(property "Value" ""
			(at 0 0 180)
			(layer "F.Fab")
			(effects
				(font
					(size 1.27 1.27)
				)
			)
		)
		(duplicate_pad_numbers_are_jumpers no)
		(fp_line
			(start 1.0414 1.575054)
			(end -1.0414 1.575054)
			(stroke
				(width 0.1524)
				(type default)
			)
			(layer "F.SilkS")
		)
		(fp_line
			(start 1.0414 -1.575054)
			(end 1.0414 1.575054)
			(stroke
				(width 0.1524)
				(type default)
			)
			(layer "F.SilkS")
		)
		(fp_line
			(start 0.254 -1.575054)
			(end 1.0414 -1.575054)
			(stroke
				(width 0.1524)
				(type default)
			)
			(layer "F.SilkS")
		)
		(fp_line
			(start 0.2286 -1.575054)
			(end 0 -1.272032)
			(stroke
				(width 0.1524)
				(type default)
			)
			(layer "F.SilkS")
		)
		(fp_line
			(start 0 -1.272032)
			(end -0.254 -1.575054)
			(stroke
				(width 0.1524)
				(type default)
			)
			(layer "F.SilkS")
		)
		(fp_line
			(start -1.0414 1.575054)
			(end -1.0414 -1.575054)
			(stroke
				(width 0.1524)
				(type default)
			)
			(layer "F.SilkS")
		)
		(fp_line
			(start -1.0414 -1.575054)
			(end -0.254 -1.575054)
			(stroke
				(width 0.1524)
				(type default)
			)
			(layer "F.SilkS")
		)
		(fp_poly
			(pts
				(xy -3.916172 -1.656588) (xy -3.32105 -2.479802) (xy -2.79527 -1.472946)
			)
			(stroke
				(width 0)
				(type default)
			)
			(fill yes)
			(layer "F.SilkS")
		)
		(fp_line
			(start 2.5654 1.2192)
			(end 1.4478 1.2192)
			(stroke
				(width 0.1)
				(type default)
			)
			(layer "F.Fab")
		)
		(fp_line
			(start 2.5654 -1.2192)
			(end 2.5654 1.2192)
			(stroke
				(width 0.1)
				(type default)
			)
			(layer "F.Fab")
		)
		(fp_line
			(start 1.4478 1.5748)
			(end -1.4478 1.5748)
			(stroke
				(width 0.1)
				(type default)
			)
			(layer "F.Fab")
		)
		(fp_line
			(start 1.4478 1.2192)
			(end 1.4478 1.5748)
			(stroke
				(width 0.1)
				(type default)
			)
			(layer "F.Fab")
		)
		(fp_line
			(start 1.4478 -1.2192)
			(end 2.5654 -1.2192)
			(stroke
				(width 0.1)
				(type default)
			)
			(layer "F.Fab")
		)
		(fp_line
			(start 1.4478 -1.5748)
			(end 1.4478 -1.2192)
			(stroke
				(width 0.1)
				(type default)
			)
			(layer "F.Fab")
		)
		(fp_line
			(start -1.4478 1.5748)
			(end -1.4478 1.2192)
			(stroke
				(width 0.1)
				(type default)
			)
			(layer "F.Fab")
		)
		(fp_line
			(start -1.4478 1.2192)
			(end -2.5654 1.2192)
			(stroke
				(width 0.1)
				(type default)
			)
			(layer "F.Fab")
		)
		(fp_line
			(start -1.4478 -1.2192)
			(end -1.4478 -1.5748)
			(stroke
				(width 0.1)
				(type default)
			)
			(layer "F.Fab")
		)
		(fp_line
			(start -1.4478 -1.5748)
			(end 1.4478 -1.5748)
			(stroke
				(width 0.1)
				(type default)
			)
			(layer "F.Fab")
		)
		(fp_line
			(start -2.5654 1.2192)
			(end -2.5654 -1.2192)
			(stroke
				(width 0.1)
				(type default)
			)
			(layer "F.Fab")
		)
		(fp_line
			(start -2.5654 -1.2192)
			(end -1.4478 -1.2192)
			(stroke
				(width 0.1)
				(type default)
			)
			(layer "F.Fab")
		)
		(fp_poly
			(pts
				(xy -2.710688 -0.975106) (xy -3.726688 -1.483106) (xy -3.726688 -0.467106)
			)
			(stroke
				(width 0)
				(type default)
			)
			(fill yes)
			(layer "F.Fab")
		)
		(pad "1" smd rect
			(at -1.849882 -0.975106 90)
			(size 0.3556 1.3208)
			(layers "F.Cu" "F.Mask" "F.Paste")
			(net "JTAG_CPU0_TDO_CPU1_TDI")
		)
		(pad "2" smd rect
			(at -1.849882 -0.32512 90)
			(size 0.3556 1.3208)
			(layers "F.Cu" "F.Mask" "F.Paste")
			(net "JTAG_CPU1_R_TDI")
		)
		(pad "3" smd rect
			(at -1.849882 0.32512 90)
			(size 0.3556 1.3208)
			(layers "F.Cu" "F.Mask" "F.Paste")
			(net "FM_PLD_CPU1_PRSNT_HDT_N")
		)
		(pad "4" smd rect
			(at -1.849882 0.975106 90)
			(size 0.3556 1.3208)
			(layers "F.Cu" "F.Mask" "F.Paste")
			(net "GND")
		)
		(pad "5" smd rect
			(at 1.849882 0.975106 90)
			(size 0.3556 1.3208)
			(layers "F.Cu" "F.Mask" "F.Paste")
			(net "JTAG_CPU0_TDO_CPU1_TDI")
		)
		(pad "6" smd rect
			(at 1.849882 0.32512 90)
			(size 0.3556 1.3208)
			(layers "F.Cu" "F.Mask" "F.Paste")
			(net "JTAG_CPU1_BYPASS")
		)
		(pad "7" smd rect
			(at 1.849882 -0.32512 90)
			(size 0.3556 1.3208)
			(layers "F.Cu" "F.Mask" "F.Paste")
			(net "CPU1_HDT_BYPASS_SEL")
		)
		(pad "8" smd rect
			(at 1.849882 -0.975106 90)
			(size 0.3556 1.3208)
			(layers "F.Cu" "F.Mask" "F.Paste")
			(net "PVDD18_S5_P0")
		)
	)
	(footprint ""
		(layer "F.Cu")
		(at 194.30619 -43.199558 180)
		(property "Reference" "Q125"
			(at 1.7526 1.856232 0)
			(unlocked yes)
			(layer "F.SilkS")
			(effects
				(font
					(size 0.7874 0.5842)
					(thickness 0.1524)
				)
				(justify left)
			)
		)
		(property "Value" ""
			(at 0 0 180)
			(layer "F.Fab")
			(effects
				(font
					(size 1.27 1.27)
				)
			)
		)
		(duplicate_pad_numbers_are_jumpers no)
		(fp_line
			(start 1.332738 1.100074)
			(end -1.332738 1.100074)
			(stroke
				(width 0.1524)
				(type default)
			)
			(layer "F.SilkS")
		)
		(fp_line
			(start 1.332738 -1.100074)
			(end 1.332738 1.100074)
			(stroke
				(width 0.1524)
				(type default)
			)
			(layer "F.SilkS")
		)
		(fp_line
			(start 0.4826 -1.100074)
			(end 1.332738 -1.100074)
			(stroke
				(width 0.1524)
				(type default)
			)
			(layer "F.SilkS")
		)
		(fp_line
			(start 0 -0.541274)
			(end 0.4826 -1.100074)
			(stroke
				(width 0.1524)
				(type default)
			)
			(layer "F.SilkS")
		)
		(fp_line
			(start -0.4826 -1.100074)
			(end 0 -0.541274)
			(stroke
				(width 0.1524)
				(type default)
			)
			(layer "F.SilkS")
		)
		(fp_line
			(start -1.332738 1.100074)
			(end -1.332738 -1.100074)
			(stroke
				(width 0.1524)
				(type default)
			)
			(layer "F.SilkS")
		)
		(fp_line
			(start -1.332738 -1.100074)
			(end -0.4826 -1.100074)
			(stroke
				(width 0.1524)
				(type default)
			)
			(layer "F.SilkS")
		)
		(fp_poly
			(pts
				(xy -1.980438 -0.69215) (xy -2.682494 -0.341122) (xy -2.682494 -1.043178)
			)
			(stroke
				(width 0)
				(type default)
			)
			(fill yes)
			(layer "F.SilkS")
		)
		(fp_line
			(start 0.674878 1.100074)
			(end -0.674878 1.100074)
			(stroke
				(width 0.1)
				(type default)
			)
			(layer "F.Fab")
		)
		(fp_line
			(start 0.674878 -1.100074)
			(end 0.674878 1.100074)
			(stroke
				(width 0.1)
				(type default)
			)
			(layer "F.Fab")
		)
		(fp_line
			(start -0.674878 1.100074)
			(end -0.674878 -1.100074)
			(stroke
				(width 0.1)
				(type default)
			)
			(layer "F.Fab")
		)
		(fp_line
			(start -0.674878 -1.100074)
			(end 0.674878 -1.100074)
			(stroke
				(width 0.1)
				(type default)
			)
			(layer "F.Fab")
		)
		(fp_poly
			(pts
				(xy -2.2352 -0.298958) (xy -2.2352 -1.001014) (xy -1.533144 -0.649986)
			)
			(stroke
				(width 0)
				(type default)
			)
			(fill yes)
			(layer "F.Fab")
		)
		(pad "1" smd rect
			(at -0.94996 -0.649986 270)
			(size 0.4318 0.508)
			(layers "F.Cu" "F.Mask" "F.Paste")
			(net "GND")
		)
		(pad "2" smd rect
			(at -0.94996 0 270)
			(size 0.4318 0.508)
			(layers "F.Cu" "F.Mask" "F.Paste")
			(net "P12V_SCM_EN_R")
		)
		(pad "3" smd rect
			(at -0.94996 0.649986 270)
			(size 0.4318 0.508)
			(layers "F.Cu" "F.Mask" "F.Paste")
			(net "P12V_SCM_UV_R")
		)
		(pad "4" smd rect
			(at 0.94996 0.649986 270)
			(size 0.4318 0.508)
			(layers "F.Cu" "F.Mask" "F.Paste")
			(net "GND")
		)
		(pad "5" smd rect
			(at 0.94996 0 270)
			(size 0.4318 0.508)
			(layers "F.Cu" "F.Mask" "F.Paste")
			(net "P12V_SCM_EN_G")
		)
		(pad "6" smd rect
			(at 0.94996 -0.649986 270)
			(size 0.4318 0.508)
			(layers "F.Cu" "F.Mask" "F.Paste")
			(net "P12V_SCM_EN_G")
		)
	)
	(footprint ""
		(layer "F.Cu")
		(at 420.75735 -41.087548)
		(property "Reference" "R5071"
			(at 0 0 0)
			(layer "F.SilkS")
			(hide yes)
			(effects
				(font
					(size 1.27 1.27)
				)
			)
		)
		(property "Value" ""
			(at 0 0 0)
			(layer "F.Fab")
			(effects
				(font
					(size 1.27 1.27)
				)
			)
		)
		(duplicate_pad_numbers_are_jumpers no)
		(fp_line
			(start -0.7874 -0.4064)
			(end 0.7874 -0.4064)
			(stroke
				(width 0.1524)
				(type default)
			)
			(layer "F.SilkS")
		)
		(fp_line
			(start -0.7874 0.4064)
			(end -0.7874 -0.4064)
			(stroke
				(width 0.1524)
				(type default)
			)
			(layer "F.SilkS")
		)
		(fp_line
			(start 0.7874 -0.4064)
			(end 0.7874 0.4064)
			(stroke
				(width 0.1524)
				(type default)
			)
			(layer "F.SilkS")
		)
		(fp_line
			(start 0.7874 0.4064)
			(end -0.7874 0.4064)
			(stroke
				(width 0.1524)
				(type default)
			)
			(layer "F.SilkS")
		)
		(fp_line
			(start -0.67945 -0.305054)
			(end -0.12065 -0.305054)
			(stroke
				(width 0.1)
				(type default)
			)
			(layer "F.Fab")
		)
		(fp_line
			(start -0.67945 0.3048)
			(end -0.67945 -0.305054)
			(stroke
				(width 0.1)
				(type default)
			)
			(layer "F.Fab")
		)
		(fp_line
			(start -0.12065 -0.305054)
			(end -0.12065 -0.2794)
			(stroke
				(width 0.1)
				(type default)
			)
			(layer "F.Fab")
		)
		(fp_line
			(start -0.12065 -0.2794)
			(end 0.12065 -0.2794)
			(stroke
				(width 0.1)
				(type default)
			)
			(layer "F.Fab")
		)
		(fp_line
			(start -0.12065 0.2794)
			(end -0.12065 0.3048)
			(stroke
				(width 0.1)
				(type default)
			)
			(layer "F.Fab")
		)
		(fp_line
			(start -0.12065 0.3048)
			(end -0.67945 0.3048)
			(stroke
				(width 0.1)
				(type default)
			)
			(layer "F.Fab")
		)
		(fp_line
			(start 0.120396 0.2794)
			(end -0.12065 0.2794)
			(stroke
				(width 0.1)
				(type default)
			)
			(layer "F.Fab")
		)
		(fp_line
			(start 0.120396 0.3048)
			(end 0.120396 0.2794)
			(stroke
				(width 0.1)
				(type default)
			)
			(layer "F.Fab")
		)
		(fp_line
			(start 0.12065 -0.3048)
			(end 0.67945 -0.3048)
			(stroke
				(width 0.1)
				(type default)
			)
			(layer "F.Fab")
		)
		(fp_line
			(start 0.12065 -0.2794)
			(end 0.12065 -0.3048)
			(stroke
				(width 0.1)
				(type default)
			)
			(layer "F.Fab")
		)
		(fp_line
			(start 0.67945 -0.3048)
			(end 0.67945 0.3048)
			(stroke
				(width 0.1)
				(type default)
			)
			(layer "F.Fab")
		)
		(fp_line
			(start 0.67945 0.3048)
			(end 0.120396 0.3048)
			(stroke
				(width 0.1)
				(type default)
			)
			(layer "F.Fab")
		)
		(pad "1" smd circle
			(at -0.40005 0)
			(size 0 0)
			(layers "F.Cu" "F.Mask" "F.Paste")
			(net "P1V8_AUX")
		)
		(pad "2" smd circle
			(at 0.40005 0)
			(size 0 0)
			(layers "F.Cu" "F.Mask" "F.Paste")
			(net "FM_FORCE_ALL_PWRON_ON")
		)
	)
	(footprint ""
		(layer "F.Cu")
		(at 257.501644 -138.448796 180)
		(property "Reference" "R607"
			(at 0 0 180)
			(layer "F.SilkS")
			(hide yes)
			(effects
				(font
					(size 1.27 1.27)
				)
			)
		)
		(property "Value" ""
			(at 0 0 180)
			(layer "F.Fab")
			(effects
				(font
					(size 1.27 1.27)
				)
			)
		)
		(duplicate_pad_numbers_are_jumpers no)
		(fp_line
			(start 0.7874 0.4064)
			(end -0.7874 0.4064)
			(stroke
				(width 0.1524)
				(type default)
			)
			(layer "F.SilkS")
		)
		(fp_line
			(start 0.7874 -0.4064)
			(end 0.7874 0.4064)
			(stroke
				(width 0.1524)
				(type default)
			)
			(layer "F.SilkS")
		)
		(fp_line
			(start -0.7874 0.4064)
			(end -0.7874 -0.4064)
			(stroke
				(width 0.1524)
				(type default)
			)
			(layer "F.SilkS")
		)
		(fp_line
			(start -0.7874 -0.4064)
			(end 0.7874 -0.4064)
			(stroke
				(width 0.1524)
				(type default)
			)
			(layer "F.SilkS")
		)
		(fp_line
			(start 0.67945 0.3048)
			(end 0.120396 0.3048)
			(stroke
				(width 0.1)
				(type default)
			)
			(layer "F.Fab")
		)
		(fp_line
			(start 0.67945 -0.3048)
			(end 0.67945 0.3048)
			(stroke
				(width 0.1)
				(type default)
			)
			(layer "F.Fab")
		)
		(fp_line
			(start 0.12065 -0.2794)
			(end 0.12065 -0.3048)
			(stroke
				(width 0.1)
				(type default)
			)
			(layer "F.Fab")
		)
		(fp_line
			(start 0.12065 -0.3048)
			(end 0.67945 -0.3048)
			(stroke
				(width 0.1)
				(type default)
			)
			(layer "F.Fab")
		)
		(fp_line
			(start 0.120396 0.3048)
			(end 0.120396 0.2794)
			(stroke
				(width 0.1)
				(type default)
			)
			(layer "F.Fab")
		)
		(fp_line
			(start 0.120396 0.2794)
			(end -0.12065 0.2794)
			(stroke
				(width 0.1)
				(type default)
			)
			(layer "F.Fab")
		)
		(fp_line
			(start -0.12065 0.3048)
			(end -0.67945 0.3048)
			(stroke
				(width 0.1)
				(type default)
			)
			(layer "F.Fab")
		)
		(fp_line
			(start -0.12065 0.2794)
			(end -0.12065 0.3048)
			(stroke
				(width 0.1)
				(type default)
			)
			(layer "F.Fab")
		)
		(fp_line
			(start -0.12065 -0.2794)
			(end 0.12065 -0.2794)
			(stroke
				(width 0.1)
				(type default)
			)
			(layer "F.Fab")
		)
		(fp_line
			(start -0.12065 -0.305054)
			(end -0.12065 -0.2794)
			(stroke
				(width 0.1)
				(type default)
			)
			(layer "F.Fab")
		)
		(fp_line
			(start -0.67945 0.3048)
			(end -0.67945 -0.305054)
			(stroke
				(width 0.1)
				(type default)
			)
			(layer "F.Fab")
		)
		(fp_line
			(start -0.67945 -0.305054)
			(end -0.12065 -0.305054)
			(stroke
				(width 0.1)
				(type default)
			)
			(layer "F.Fab")
		)
		(pad "1" smd circle
			(at -0.40005 0 180)
			(size 0 0)
			(layers "F.Cu" "F.Mask" "F.Paste")
			(net "SPI_CPU0_LVC3_D3")
		)
		(pad "2" smd circle
			(at 0.40005 0 180)
			(size 0 0)
			(layers "F.Cu" "F.Mask" "F.Paste")
			(net "SPI_CPU0_LVC3_SCM_D3")
		)
	)
	(footprint ""
		(layer "F.Cu")
		(at 291.816282 -364.891066)
		(property "Reference" "PC148"
			(at 0 0 0)
			(layer "F.SilkS")
			(hide yes)
			(effects
				(font
					(size 1.27 1.27)
				)
			)
		)
		(property "Value" ""
			(at 0 0 0)
			(layer "F.Fab")
			(effects
				(font
					(size 1.27 1.27)
				)
			)
		)
		(duplicate_pad_numbers_are_jumpers no)
		(fp_line
			(start -0.7874 -0.4064)
			(end 0.7874 -0.4064)
			(stroke
				(width 0.1524)
				(type default)
			)
			(layer "F.SilkS")
		)
		(fp_line
			(start -0.7874 0.4064)
			(end -0.7874 -0.4064)
			(stroke
				(width 0.1524)
				(type default)
			)
			(layer "F.SilkS")
		)
		(fp_line
			(start 0.7874 -0.4064)
			(end 0.7874 0.4064)
			(stroke
				(width 0.1524)
				(type default)
			)
			(layer "F.SilkS")
		)
		(fp_line
			(start 0.7874 0.4064)
			(end -0.7874 0.4064)
			(stroke
				(width 0.1524)
				(type default)
			)
			(layer "F.SilkS")
		)
		(fp_line
			(start -0.67945 -0.305054)
			(end -0.12065 -0.305054)
			(stroke
				(width 0.1)
				(type default)
			)
			(layer "F.Fab")
		)
		(fp_line
			(start -0.67945 0.3048)
			(end -0.67945 -0.305054)
			(stroke
				(width 0.1)
				(type default)
			)
			(layer "F.Fab")
		)
		(fp_line
			(start -0.12065 -0.305054)
			(end -0.12065 -0.2794)
			(stroke
				(width 0.1)
				(type default)
			)
			(layer "F.Fab")
		)
		(fp_line
			(start -0.12065 -0.2794)
			(end 0.12065 -0.2794)
			(stroke
				(width 0.1)
				(type default)
			)
			(layer "F.Fab")
		)
		(fp_line
			(start -0.12065 0.2794)
			(end -0.12065 0.3048)
			(stroke
				(width 0.1)
				(type default)
			)
			(layer "F.Fab")
		)
		(fp_line
			(start -0.12065 0.3048)
			(end -0.67945 0.3048)
			(stroke
				(width 0.1)
				(type default)
			)
			(layer "F.Fab")
		)
		(fp_line
			(start 0.120396 0.2794)
			(end -0.12065 0.2794)
			(stroke
				(width 0.1)
				(type default)
			)
			(layer "F.Fab")
		)
		(fp_line
			(start 0.120396 0.3048)
			(end 0.120396 0.2794)
			(stroke
				(width 0.1)
				(type default)
			)
			(layer "F.Fab")
		)
		(fp_line
			(start 0.12065 -0.3048)
			(end 0.67945 -0.3048)
			(stroke
				(width 0.1)
				(type default)
			)
			(layer "F.Fab")
		)
		(fp_line
			(start 0.12065 -0.2794)
			(end 0.12065 -0.3048)
			(stroke
				(width 0.1)
				(type default)
			)
			(layer "F.Fab")
		)
		(fp_line
			(start 0.67945 -0.3048)
			(end 0.67945 0.3048)
			(stroke
				(width 0.1)
				(type default)
			)
			(layer "F.Fab")
		)
		(fp_line
			(start 0.67945 0.3048)
			(end 0.120396 0.3048)
			(stroke
				(width 0.1)
				(type default)
			)
			(layer "F.Fab")
		)
		(pad "1" smd circle
			(at -0.40005 0)
			(size 0 0)
			(layers "F.Cu" "F.Mask" "F.Paste")
			(net "P12V_AUX")
		)
		(pad "2" smd circle
			(at 0.40005 0)
			(size 0 0)
			(layers "F.Cu" "F.Mask" "F.Paste")
			(net "GND")
		)
	)
)
